(kicad_pcb
	(version 20260206)
	(generator "pcbnew")
	(generator_version "10.0")
	(general
		(thickness 1.6)
		(legacy_teardrops no)
	)
	(paper "A4")
	(title_block
		(title "Bryce Canyon_SCC_16316-1_OCP.brd")
		(comment 1 "Bryce Canyon / footprints 119-126 of 1561")
	)
	(layers
		(0 "F.Cu" signal "TOP")
		(4 "In1.Cu" signal "L2GND")
		(6 "In2.Cu" signal "L3")
		(8 "In3.Cu" signal "L4VCC")
		(10 "In4.Cu" signal "L5VCC")
		(12 "In5.Cu" signal "L6")
		(14 "In6.Cu" signal "L7GND")
		(2 "B.Cu" signal "BOTTOM")
		(9 "F.Adhes" user "F.Adhesive")
		(11 "B.Adhes" user "B.Adhesive")
		(13 "F.Paste" user "Package Geometry/Pastemask Top")
		(15 "B.Paste" user "Package Geometry/Pastemask Bottom")
		(5 "F.SilkS" user "Ref Des/Silkscreen Top")
		(7 "B.SilkS" user "Ref Des/Silkscreen Bottom")
		(1 "F.Mask" user "Board Geometry/Soldermask Top")
		(3 "B.Mask" user "Board Geometry/Soldermask Bottom")
		(17 "Dwgs.User" user "User.Drawings")
		(19 "Cmts.User" user "User.Comments")
		(21 "Eco1.User" user "User.Eco1")
		(23 "Eco2.User" user "User.Eco2")
		(25 "Edge.Cuts" user "Board Geometry/Outline")
		(27 "Margin" user)
		(31 "F.CrtYd" user "Package Geometry/Place Bound Top")
		(29 "B.CrtYd" user "Package Geometry/Place Bound Bottom")
		(35 "F.Fab" user "Ref Des/Assembly Top")
		(33 "B.Fab" user "Ref Des/Assembly Bottom")
	)
	(footprint ""
		(layer "F.Cu")
		(at 171.517056 -55.113428)
		(property "Reference" "TP154"
			(at 0 0 0)
			(layer "F.SilkS")
			(hide yes)
			(effects
				(font
					(size 1.27 1.27)
				)
			)
		)
		(property "Value" "TPAD28-2-GP"
			(at -0.0127 -1.6637 0)
			(unlocked yes)
			(layer "F.Fab")
			(hide yes)
			(effects
				(font
					(size 1.016 1.016)
					(thickness 0.1524)
				)
			)
		)
		(property "Device Type" "TPAD28"
			(at -0.0127 -3.1877 0)
			(unlocked yes)
			(layer "F.Fab")
			(hide yes)
			(effects
				(font
					(size 1.016 1.016)
					(thickness 0.1524)
				)
			)
		)
		(duplicate_pad_numbers_are_jumpers no)
		(fp_poly
			(pts
				(arc
					(start 0.3556 0)
					(mid -0.3556 0)
					(end 0.3556 0)
				)
			)
			(stroke
				(width 0)
				(type default)
			)
			(fill no)
			(layer "F.CrtYd")
		)
		(fp_poly
			(pts
				(arc
					(start 0.6096 0)
					(mid -0.6096 0)
					(end 0.6096 0)
				)
			)
			(stroke
				(width 0)
				(type default)
			)
			(fill no)
			(layer "F.Fab")
		)
		(pad "1" smd circle
			(at 0 0)
			(size 0.7112 0.7112)
			(layers "F.Cu" "F.Mask" "F.Paste")
			(net "PG_CORE")
		)
	)
	(footprint ""
		(layer "F.Cu")
		(at 176.62652 -108.3437)
		(property "Reference" "R444"
			(at 0 0 0)
			(layer "F.SilkS")
			(hide yes)
			(effects
				(font
					(size 1.27 1.27)
				)
			)
		)
		(property "Value" "0R2J-2-GP"
			(at 0.064008 -3.993896 0)
			(unlocked yes)
			(layer "F.Fab")
			(hide yes)
			(effects
				(font
					(size 1.016 1.016)
					(thickness 0.1524)
				)
			)
		)
		(property "Device Type" "R402H16"
			(at 0.064008 -5.517896 0)
			(unlocked yes)
			(layer "F.Fab")
			(hide yes)
			(effects
				(font
					(size 1.016 1.016)
					(thickness 0.1524)
				)
			)
		)
		(duplicate_pad_numbers_are_jumpers no)
		(fp_line
			(start -0.508 -0.9398)
			(end -0.508 0.9398)
			(stroke
				(width 0.1524)
				(type default)
			)
			(layer "F.SilkS")
		)
		(fp_line
			(start 0.508 -0.9398)
			(end -0.508 -0.9398)
			(stroke
				(width 0.1524)
				(type default)
			)
			(layer "F.SilkS")
		)
		(fp_rect
			(start -0.508 0.9398)
			(end 0.508 -0.9398)
			(stroke
				(width 0)
				(type default)
			)
			(fill no)
			(layer "F.CrtYd")
		)
		(fp_rect
			(start -0.508 0.9398)
			(end 0.508 -0.9398)
			(stroke
				(width 0)
				(type default)
			)
			(fill no)
			(layer "F.Fab")
		)
		(pad "1" smd custom
			(at 0 -0.4445)
			(size 0.1397 0.1397)
			(layers "F.Cu" "F.Mask" "F.Paste")
			(net "P1V8_C_PG_LS")
			(options
				(clearance outline)
				(anchor circle)
			)
			(primitives
				(gr_poly
					(pts
						(arc
							(start -0.1778 -0.2794)
							(mid -0.249642 -0.249642)
							(end -0.2794 -0.1778)
						)
						(arc
							(start -0.2794 0.1778)
							(mid -0.249642 0.249642)
							(end -0.1778 0.2794)
						)
						(arc
							(start 0.1778 0.2794)
							(mid 0.249642 0.249642)
							(end 0.2794 0.1778)
						)
						(arc
							(start 0.2794 -0.1778)
							(mid 0.249642 -0.249642)
							(end 0.1778 -0.2794)
						)
					)
					(width 0)
					(fill yes)
				)
			)
		)
		(pad "2" smd custom
			(at 0 0.4445)
			(size 0.1397 0.1397)
			(layers "F.Cu" "F.Mask" "F.Paste")
			(net "Q22_D")
			(options
				(clearance outline)
				(anchor circle)
			)
			(primitives
				(gr_poly
					(pts
						(arc
							(start -0.1778 -0.2794)
							(mid -0.249642 -0.249642)
							(end -0.2794 -0.1778)
						)
						(arc
							(start -0.2794 0.1778)
							(mid -0.249642 0.249642)
							(end -0.1778 0.2794)
						)
						(arc
							(start 0.1778 0.2794)
							(mid 0.249642 0.249642)
							(end 0.2794 0.1778)
						)
						(arc
							(start 0.2794 -0.1778)
							(mid 0.249642 -0.249642)
							(end 0.1778 -0.2794)
						)
					)
					(width 0)
					(fill yes)
				)
			)
		)
	)
	(footprint ""
		(layer "F.Cu")
		(at 119.378984 -89.588848 180)
		(property "Reference" "R46"
			(at 0 0 180)
			(layer "F.SilkS")
			(hide yes)
			(effects
				(font
					(size 1.27 1.27)
				)
			)
		)
		(property "Value" "4K7R2F-GP"
			(at 0.064008 -3.993896 180)
			(unlocked yes)
			(layer "F.Fab")
			(hide yes)
			(effects
				(font
					(size 1.016 1.016)
					(thickness 0.1524)
				)
			)
		)
		(property "Device Type" "R402H16"
			(at 0.064008 -5.517896 180)
			(unlocked yes)
			(layer "F.Fab")
			(hide yes)
			(effects
				(font
					(size 1.016 1.016)
					(thickness 0.1524)
				)
			)
		)
		(duplicate_pad_numbers_are_jumpers no)
		(fp_line
			(start 0.508 -0.9398)
			(end -0.508 -0.9398)
			(stroke
				(width 0.1524)
				(type default)
			)
			(layer "F.SilkS")
		)
		(fp_line
			(start -0.508 -0.9398)
			(end -0.508 0.9398)
			(stroke
				(width 0.1524)
				(type default)
			)
			(layer "F.SilkS")
		)
		(fp_rect
			(start -0.508 0.9398)
			(end 0.508 -0.9398)
			(stroke
				(width 0)
				(type default)
			)
			(fill no)
			(layer "F.CrtYd")
		)
		(fp_rect
			(start -0.508 0.9398)
			(end 0.508 -0.9398)
			(stroke
				(width 0)
				(type default)
			)
			(fill no)
			(layer "F.Fab")
		)
		(pad "1" smd custom
			(at 0 -0.4445 180)
			(size 0.1397 0.1397)
			(layers "F.Cu" "F.Mask" "F.Paste")
			(net "EXP_GPIO15")
			(options
				(clearance outline)
				(anchor circle)
			)
			(primitives
				(gr_poly
					(pts
						(arc
							(start -0.1778 -0.2794)
							(mid -0.249642 -0.249642)
							(end -0.2794 -0.1778)
						)
						(arc
							(start -0.2794 0.1778)
							(mid -0.249642 0.249642)
							(end -0.1778 0.2794)
						)
						(arc
							(start 0.1778 0.2794)
							(mid 0.249642 0.249642)
							(end 0.2794 0.1778)
						)
						(arc
							(start 0.2794 -0.1778)
							(mid 0.249642 -0.249642)
							(end 0.1778 -0.2794)
						)
					)
					(width 0)
					(fill yes)
				)
			)
		)
		(pad "2" smd custom
			(at 0 0.4445 180)
			(size 0.1397 0.1397)
			(layers "F.Cu" "F.Mask" "F.Paste")
			(net "GND")
			(options
				(clearance outline)
				(anchor circle)
			)
			(primitives
				(gr_poly
					(pts
						(arc
							(start -0.1778 -0.2794)
							(mid -0.249642 -0.249642)
							(end -0.2794 -0.1778)
						)
						(arc
							(start -0.2794 0.1778)
							(mid -0.249642 0.249642)
							(end -0.1778 0.2794)
						)
						(arc
							(start 0.1778 0.2794)
							(mid 0.249642 0.249642)
							(end 0.2794 0.1778)
						)
						(arc
							(start 0.2794 -0.1778)
							(mid 0.249642 -0.249642)
							(end 0.1778 -0.2794)
						)
					)
					(width 0)
					(fill yes)
				)
			)
		)
	)
	(footprint ""
		(layer "F.Cu")
		(at 155.1051 -100.38588 90)
		(property "Reference" "R293"
			(at 0 0 90)
			(layer "F.SilkS")
			(hide yes)
			(effects
				(font
					(size 1.27 1.27)
				)
			)
		)
		(property "Value" "0R2J-2-GP"
			(at 0.064008 -3.993896 90)
			(unlocked yes)
			(layer "F.Fab")
			(hide yes)
			(effects
				(font
					(size 1.016 1.016)
					(thickness 0.1524)
				)
			)
		)
		(property "Device Type" "R402H16"
			(at 0.064008 -5.517896 90)
			(unlocked yes)
			(layer "F.Fab")
			(hide yes)
			(effects
				(font
					(size 1.016 1.016)
					(thickness 0.1524)
				)
			)
		)
		(duplicate_pad_numbers_are_jumpers no)
		(fp_line
			(start 0.508 -0.9398)
			(end -0.508 -0.9398)
			(stroke
				(width 0.1524)
				(type default)
			)
			(layer "F.SilkS")
		)
		(fp_line
			(start -0.508 -0.9398)
			(end -0.508 0.9398)
			(stroke
				(width 0.1524)
				(type default)
			)
			(layer "F.SilkS")
		)
		(fp_rect
			(start -0.508 0.9398)
			(end 0.508 -0.9398)
			(stroke
				(width 0)
				(type default)
			)
			(fill no)
			(layer "F.CrtYd")
		)
		(fp_rect
			(start -0.508 0.9398)
			(end 0.508 -0.9398)
			(stroke
				(width 0)
				(type default)
			)
			(fill no)
			(layer "F.Fab")
		)
		(pad "1" smd custom
			(at 0 -0.4445 90)
			(size 0.1397 0.1397)
			(layers "F.Cu" "F.Mask" "F.Paste")
			(net "UART_SDB_TX")
			(options
				(clearance outline)
				(anchor circle)
			)
			(primitives
				(gr_poly
					(pts
						(arc
							(start -0.1778 -0.2794)
							(mid -0.249642 -0.249642)
							(end -0.2794 -0.1778)
						)
						(arc
							(start -0.2794 0.1778)
							(mid -0.249642 0.249642)
							(end -0.1778 0.2794)
						)
						(arc
							(start 0.1778 0.2794)
							(mid 0.249642 0.249642)
							(end 0.2794 0.1778)
						)
						(arc
							(start 0.2794 -0.1778)
							(mid 0.249642 -0.249642)
							(end 0.1778 -0.2794)
						)
					)
					(width 0)
					(fill yes)
				)
			)
		)
		(pad "2" smd custom
			(at 0 0.4445 90)
			(size 0.1397 0.1397)
			(layers "F.Cu" "F.Mask" "F.Paste")
			(net "SAS_R_SDBTX")
			(options
				(clearance outline)
				(anchor circle)
			)
			(primitives
				(gr_poly
					(pts
						(arc
							(start -0.1778 -0.2794)
							(mid -0.249642 -0.249642)
							(end -0.2794 -0.1778)
						)
						(arc
							(start -0.2794 0.1778)
							(mid -0.249642 0.249642)
							(end -0.1778 0.2794)
						)
						(arc
							(start 0.1778 0.2794)
							(mid 0.249642 0.249642)
							(end 0.2794 0.1778)
						)
						(arc
							(start 0.2794 -0.1778)
							(mid 0.249642 -0.249642)
							(end 0.1778 -0.2794)
						)
					)
					(width 0)
					(fill yes)
				)
			)
		)
	)
	(footprint ""
		(layer "F.Cu")
		(at 39.8018 -34.163 180)
		(property "Reference" "R383"
			(at 0 0 180)
			(layer "F.SilkS")
			(hide yes)
			(effects
				(font
					(size 1.27 1.27)
				)
			)
		)
		(property "Value" "0R2J-2-GP"
			(at 0.064008 -3.993896 180)
			(unlocked yes)
			(layer "F.Fab")
			(hide yes)
			(effects
				(font
					(size 1.016 1.016)
					(thickness 0.1524)
				)
			)
		)
		(property "Device Type" "R402H16"
			(at 0.064008 -5.517896 180)
			(unlocked yes)
			(layer "F.Fab")
			(hide yes)
			(effects
				(font
					(size 1.016 1.016)
					(thickness 0.1524)
				)
			)
		)
		(duplicate_pad_numbers_are_jumpers no)
		(fp_line
			(start 0.508 -0.9398)
			(end -0.508 -0.9398)
			(stroke
				(width 0.1524)
				(type default)
			)
			(layer "F.SilkS")
		)
		(fp_line
			(start -0.508 -0.9398)
			(end -0.508 0.9398)
			(stroke
				(width 0.1524)
				(type default)
			)
			(layer "F.SilkS")
		)
		(fp_rect
			(start -0.508 0.9398)
			(end 0.508 -0.9398)
			(stroke
				(width 0)
				(type default)
			)
			(fill no)
			(layer "F.CrtYd")
		)
		(fp_rect
			(start -0.508 0.9398)
			(end 0.508 -0.9398)
			(stroke
				(width 0)
				(type default)
			)
			(fill no)
			(layer "F.Fab")
		)
		(pad "1" smd custom
			(at 0 -0.4445 180)
			(size 0.1397 0.1397)
			(layers "F.Cu" "F.Mask" "F.Paste")
			(net "P1V5_E_PG")
			(options
				(clearance outline)
				(anchor circle)
			)
			(primitives
				(gr_poly
					(pts
						(arc
							(start -0.1778 -0.2794)
							(mid -0.249642 -0.249642)
							(end -0.2794 -0.1778)
						)
						(arc
							(start -0.2794 0.1778)
							(mid -0.249642 0.249642)
							(end -0.1778 0.2794)
						)
						(arc
							(start 0.1778 0.2794)
							(mid 0.249642 0.249642)
							(end 0.2794 0.1778)
						)
						(arc
							(start 0.2794 -0.1778)
							(mid 0.249642 -0.249642)
							(end 0.1778 -0.2794)
						)
					)
					(width 0)
					(fill yes)
				)
			)
		)
		(pad "2" smd custom
			(at 0 0.4445 180)
			(size 0.1397 0.1397)
			(layers "F.Cu" "F.Mask" "F.Paste")
			(net "P0V9_EN")
			(options
				(clearance outline)
				(anchor circle)
			)
			(primitives
				(gr_poly
					(pts
						(arc
							(start -0.1778 -0.2794)
							(mid -0.249642 -0.249642)
							(end -0.2794 -0.1778)
						)
						(arc
							(start -0.2794 0.1778)
							(mid -0.249642 0.249642)
							(end -0.1778 0.2794)
						)
						(arc
							(start 0.1778 0.2794)
							(mid 0.249642 0.249642)
							(end 0.2794 0.1778)
						)
						(arc
							(start 0.2794 -0.1778)
							(mid 0.249642 -0.249642)
							(end 0.1778 -0.2794)
						)
					)
					(width 0)
					(fill yes)
				)
			)
		)
	)
	(footprint ""
		(layer "F.Cu")
		(at 145.6182 -124.3838 90)
		(property "Reference" "R29"
			(at 0 0 90)
			(layer "F.SilkS")
			(hide yes)
			(effects
				(font
					(size 1.27 1.27)
				)
			)
		)
		(property "Value" "10R3F-GP"
			(at -0.0254 -2.5146 90)
			(unlocked yes)
			(layer "F.Fab")
			(hide yes)
			(effects
				(font
					(size 1.016 1.016)
					(thickness 0.1524)
				)
			)
		)
		(property "Device Type" "R603H22"
			(at -0.0254 -4.0386 90)
			(unlocked yes)
			(layer "F.Fab")
			(hide yes)
			(effects
				(font
					(size 1.016 1.016)
					(thickness 0.1524)
				)
			)
		)
		(duplicate_pad_numbers_are_jumpers no)
		(fp_line
			(start 0.2032 0)
			(end 0.4826 0)
			(stroke
				(width 0.2032)
				(type default)
			)
			(layer "F.SilkS")
		)
		(fp_line
			(start -0.4826 0)
			(end -0.2032 0)
			(stroke
				(width 0.2032)
				(type default)
			)
			(layer "F.SilkS")
		)
		(fp_rect
			(start -0.5842 1.3335)
			(end 0.5842 -1.3335)
			(stroke
				(width 0)
				(type default)
			)
			(fill no)
			(layer "F.CrtYd")
		)
		(fp_rect
			(start -0.5842 1.3335)
			(end 0.5842 -1.3335)
			(stroke
				(width 0)
				(type default)
			)
			(fill no)
			(layer "F.Fab")
		)
		(pad "1" smd custom
			(at 0 -0.762 90)
			(size 0.2159 0.2159)
			(layers "F.Cu" "F.Mask" "F.Paste")
			(net "P1V5_E_OUT")
			(options
				(clearance outline)
				(anchor circle)
			)
			(primitives
				(gr_poly
					(pts
						(arc
							(start -0.3302 -0.4318)
							(mid -0.402042 -0.402042)
							(end -0.4318 -0.3302)
						)
						(arc
							(start -0.4318 0.3302)
							(mid -0.402042 0.402042)
							(end -0.3302 0.4318)
						)
						(arc
							(start 0.3302 0.4318)
							(mid 0.402042 0.402042)
							(end 0.4318 0.3302)
						)
						(arc
							(start 0.4318 -0.3302)
							(mid 0.402042 -0.402042)
							(end 0.3302 -0.4318)
						)
					)
					(width 0)
					(fill yes)
				)
			)
		)
		(pad "2" smd custom
			(at 0 0.762 90)
			(size 0.2159 0.2159)
			(layers "F.Cu" "F.Mask" "F.Paste")
			(net "P1V5_E_VFB_R")
			(options
				(clearance outline)
				(anchor circle)
			)
			(primitives
				(gr_poly
					(pts
						(arc
							(start -0.3302 -0.4318)
							(mid -0.402042 -0.402042)
							(end -0.4318 -0.3302)
						)
						(arc
							(start -0.4318 0.3302)
							(mid -0.402042 0.402042)
							(end -0.3302 0.4318)
						)
						(arc
							(start 0.3302 0.4318)
							(mid 0.402042 0.402042)
							(end 0.4318 0.3302)
						)
						(arc
							(start 0.4318 -0.3302)
							(mid 0.402042 -0.402042)
							(end 0.3302 -0.4318)
						)
					)
					(width 0)
					(fill yes)
				)
			)
		)
	)
	(footprint ""
		(layer "F.Cu")
		(at 163.446968 -22.462744 180)
		(property "Reference" "R174"
			(at 0 0 180)
			(layer "F.SilkS")
			(hide yes)
			(effects
				(font
					(size 1.27 1.27)
				)
			)
		)
		(property "Value" "0R2J-2-GP"
			(at 0.064008 -3.993896 180)
			(unlocked yes)
			(layer "F.Fab")
			(hide yes)
			(effects
				(font
					(size 1.016 1.016)
					(thickness 0.1524)
				)
			)
		)
		(property "Device Type" "R402H16"
			(at 0.064008 -5.517896 180)
			(unlocked yes)
			(layer "F.Fab")
			(hide yes)
			(effects
				(font
					(size 1.016 1.016)
					(thickness 0.1524)
				)
			)
		)
		(duplicate_pad_numbers_are_jumpers no)
		(fp_line
			(start 0.508 -0.9398)
			(end -0.508 -0.9398)
			(stroke
				(width 0.1524)
				(type default)
			)
			(layer "F.SilkS")
		)
		(fp_line
			(start -0.508 -0.9398)
			(end -0.508 0.9398)
			(stroke
				(width 0.1524)
				(type default)
			)
			(layer "F.SilkS")
		)
		(fp_rect
			(start -0.508 0.9398)
			(end 0.508 -0.9398)
			(stroke
				(width 0)
				(type default)
			)
			(fill no)
			(layer "F.CrtYd")
		)
		(fp_rect
			(start -0.508 0.9398)
			(end 0.508 -0.9398)
			(stroke
				(width 0)
				(type default)
			)
			(fill no)
			(layer "F.Fab")
		)
		(pad "1" smd custom
			(at 0 -0.4445 180)
			(size 0.1397 0.1397)
			(layers "F.Cu" "F.Mask" "F.Paste")
			(net "PCIE_COMP_TO_SCC_CLK_0_DN")
			(options
				(clearance outline)
				(anchor circle)
			)
			(primitives
				(gr_poly
					(pts
						(arc
							(start -0.1778 -0.2794)
							(mid -0.249642 -0.249642)
							(end -0.2794 -0.1778)
						)
						(arc
							(start -0.2794 0.1778)
							(mid -0.249642 0.249642)
							(end -0.1778 0.2794)
						)
						(arc
							(start 0.1778 0.2794)
							(mid 0.249642 0.249642)
							(end 0.2794 0.1778)
						)
						(arc
							(start 0.2794 -0.1778)
							(mid 0.249642 -0.249642)
							(end 0.1778 -0.2794)
						)
					)
					(width 0)
					(fill yes)
				)
			)
		)
		(pad "2" smd custom
			(at 0 0.4445 180)
			(size 0.1397 0.1397)
			(layers "F.Cu" "F.Mask" "F.Paste")
			(net "PCIE_CLK_R_N")
			(options
				(clearance outline)
				(anchor circle)
			)
			(primitives
				(gr_poly
					(pts
						(arc
							(start -0.1778 -0.2794)
							(mid -0.249642 -0.249642)
							(end -0.2794 -0.1778)
						)
						(arc
							(start -0.2794 0.1778)
							(mid -0.249642 0.249642)
							(end -0.1778 0.2794)
						)
						(arc
							(start 0.1778 0.2794)
							(mid 0.249642 0.249642)
							(end 0.2794 0.1778)
						)
						(arc
							(start 0.2794 -0.1778)
							(mid 0.249642 -0.249642)
							(end 0.1778 -0.2794)
						)
					)
					(width 0)
					(fill yes)
				)
			)
		)
	)
	(footprint ""
		(layer "F.Cu")
		(at 11.811 -47.0408 180)
		(property "Reference" "R523"
			(at 0 0 180)
			(layer "F.SilkS")
			(hide yes)
			(effects
				(font
					(size 1.27 1.27)
				)
			)
		)
		(property "Value" "10R2F-L-GP"
			(at 0.064008 -3.993896 180)
			(unlocked yes)
			(layer "F.Fab")
			(hide yes)
			(effects
				(font
					(size 1.016 1.016)
					(thickness 0.1524)
				)
			)
		)
		(property "Device Type" "R402H14"
			(at 0.064008 -5.517896 180)
			(unlocked yes)
			(layer "F.Fab")
			(hide yes)
			(effects
				(font
					(size 1.016 1.016)
					(thickness 0.1524)
				)
			)
		)
		(duplicate_pad_numbers_are_jumpers no)
		(fp_line
			(start 0.508 -0.9398)
			(end -0.508 -0.9398)
			(stroke
				(width 0.1524)
				(type default)
			)
			(layer "F.SilkS")
		)
		(fp_line
			(start -0.508 -0.9398)
			(end -0.508 0.9398)
			(stroke
				(width 0.1524)
				(type default)
			)
			(layer "F.SilkS")
		)
		(fp_rect
			(start -0.508 0.9398)
			(end 0.508 -0.9398)
			(stroke
				(width 0)
				(type default)
			)
			(fill no)
			(layer "F.CrtYd")
		)
		(fp_rect
			(start -0.508 0.9398)
			(end 0.508 -0.9398)
			(stroke
				(width 0)
				(type default)
			)
			(fill no)
			(layer "F.Fab")
		)
		(pad "1" smd custom
			(at 0 -0.4445 180)
			(size 0.1397 0.1397)
			(layers "F.Cu" "F.Mask" "F.Paste")
			(net "MB0_CM_SENSE_R1_N")
			(options
				(clearance outline)
				(anchor circle)
			)
			(primitives
				(gr_poly
					(pts
						(arc
							(start -0.1778 -0.2794)
							(mid -0.249642 -0.249642)
							(end -0.2794 -0.1778)
						)
						(arc
							(start -0.2794 0.1778)
							(mid -0.249642 0.249642)
							(end -0.1778 0.2794)
						)
						(arc
							(start 0.1778 0.2794)
							(mid 0.249642 0.249642)
							(end 0.2794 0.1778)
						)
						(arc
							(start 0.2794 -0.1778)
							(mid 0.249642 -0.249642)
							(end 0.1778 -0.2794)
						)
					)
					(width 0)
					(fill yes)
				)
			)
		)
		(pad "2" smd custom
			(at 0 0.4445 180)
			(size 0.1397 0.1397)
			(layers "F.Cu" "F.Mask" "F.Paste")
			(net "MB0_HS_SENSE_N")
			(options
				(clearance outline)
				(anchor circle)
			)
			(primitives
				(gr_poly
					(pts
						(arc
							(start -0.1778 -0.2794)
							(mid -0.249642 -0.249642)
							(end -0.2794 -0.1778)
						)
						(arc
							(start -0.2794 0.1778)
							(mid -0.249642 0.249642)
							(end -0.1778 0.2794)
						)
						(arc
							(start 0.1778 0.2794)
							(mid 0.249642 0.249642)
							(end 0.2794 0.1778)
						)
						(arc
							(start 0.2794 -0.1778)
							(mid 0.249642 -0.249642)
							(end 0.1778 -0.2794)
						)
					)
					(width 0)
					(fill yes)
				)
			)
		)
	)
)
